# S9S_MB_2U (Grand Teton) — schematic netlist excerpt (pin names and nets, part order shuffled) for the footprints in the layout excerpt that follows; sources: Cadence DE-HDL packaged netlist, KiCad conversion of 03242023_DA0F0TMBIJ0_F0T_Motherboard_J_brd_V01_OCP.brd

R3707  Q_RES  1K 1% CHIP  pkg 0402LF  page 233 : A = PCA9548_PCIE0_ADDR1 ; B = GND
C1517  Q_CAP_DIFFBUS  DIFF BUS_0.22UF 6.3V 20% X6S  pkg C0201  page 177 : \1\ = P5E_CPU1_PE3_TX_C_DP<15> ; \2\ = P5E_CPU1_PE3_TX_DP<15>
R3073  Q_RES  130 1% CHIP  pkg 0402LF  page 252 : A = LED_FM_PCH_SLP_S4_N ; B = P3V3_AUX

(kicad_pcb
	(version 20260206)
	(generator "pcbnew")
	(generator_version "10.0")
	(general
		(thickness 1.6)
		(legacy_teardrops no)
	)
	(paper "A4")
	(title_block
		(title "03242023_DA0F0TMBIJ0_F0T_Motherboard_J_brd_V01_OCP.brd")
		(comment 1 "Grand Teton / footprints 2273-2275 of 6105")
	)
	(layers
		(0 "F.Cu" signal "TOP")
		(4 "In1.Cu" signal "GND")
		(6 "In2.Cu" signal "IN1")
		(8 "In3.Cu" signal "GND1")
		(10 "In4.Cu" signal "IN2")
		(12 "In5.Cu" signal "GND2")
		(14 "In6.Cu" signal "IN3")
		(16 "In7.Cu" signal "GND3")
		(18 "In8.Cu" signal "VCC")
		(20 "In9.Cu" signal "VCC1")
		(22 "In10.Cu" signal "GND4")
		(24 "In11.Cu" signal "IN4")
		(26 "In12.Cu" signal "GND5")
		(28 "In13.Cu" signal "IN5")
		(30 "In14.Cu" signal "GND6")
		(32 "In15.Cu" signal "IN6")
		(34 "In16.Cu" signal "GND7")
		(2 "B.Cu" signal "BOTTOM")
		(9 "F.Adhes" user "F.Adhesive")
		(11 "B.Adhes" user "B.Adhesive")
		(13 "F.Paste" user "Package Geometry/Pastemask Top")
		(15 "B.Paste" user "Package Geometry/Pastemask Bottom")
		(5 "F.SilkS" user "Ref Des/Silkscreen Top")
		(7 "B.SilkS" user "Ref Des/Silkscreen Bottom")
		(1 "F.Mask" user "Board Geometry/Soldermask Top")
		(3 "B.Mask" user "Board Geometry/Soldermask Bottom")
		(17 "Dwgs.User" user "User.Drawings")
		(19 "Cmts.User" user "User.Comments")
		(21 "Eco1.User" user "User.Eco1")
		(23 "Eco2.User" user "User.Eco2")
		(25 "Edge.Cuts" user "Board Geometry/Outline")
		(27 "Margin" user)
		(31 "F.CrtYd" user "Package Geometry/Place Bound Top")
		(29 "B.CrtYd" user "Package Geometry/Place Bound Bottom")
		(35 "F.Fab" user "Ref Des/Assembly Top")
		(33 "B.Fab" user "Ref Des/Assembly Bottom")
	)
	(footprint ""
		(layer "F.Cu")
		(at 99.589082 -74.911966 -90)
		(property "Reference" "R3073"
			(at 0 0 270)
			(layer "F.SilkS")
			(hide yes)
			(effects
				(font
					(size 1.27 1.27)
				)
			)
		)
		(property "Value" ""
			(at 0 0 270)
			(layer "F.Fab")
			(effects
				(font
					(size 1.27 1.27)
				)
			)
		)
		(duplicate_pad_numbers_are_jumpers no)
		(fp_line
			(start -0.7874 0.4064)
			(end -0.7874 -0.4064)
			(stroke
				(width 0.1524)
				(type default)
			)
			(layer "F.SilkS")
		)
		(fp_line
			(start 0.7874 0.4064)
			(end -0.7874 0.4064)
			(stroke
				(width 0.1524)
				(type default)
			)
			(layer "F.SilkS")
		)
		(fp_line
			(start -0.7874 -0.4064)
			(end 0.7874 -0.4064)
			(stroke
				(width 0.1524)
				(type default)
			)
			(layer "F.SilkS")
		)
		(fp_line
			(start 0.7874 -0.4064)
			(end 0.7874 0.4064)
			(stroke
				(width 0.1524)
				(type default)
			)
			(layer "F.SilkS")
		)
		(fp_line
			(start -0.67945 0.3048)
			(end -0.67945 -0.305054)
			(stroke
				(width 0.1)
				(type default)
			)
			(layer "F.Fab")
		)
		(fp_line
			(start -0.12065 0.3048)
			(end -0.67945 0.3048)
			(stroke
				(width 0.1)
				(type default)
			)
			(layer "F.Fab")
		)
		(fp_line
			(start 0.120396 0.3048)
			(end 0.120396 0.2794)
			(stroke
				(width 0.1)
				(type default)
			)
			(layer "F.Fab")
		)
		(fp_line
			(start 0.67945 0.3048)
			(end 0.120396 0.3048)
			(stroke
				(width 0.1)
				(type default)
			)
			(layer "F.Fab")
		)
		(fp_line
			(start -0.12065 0.2794)
			(end -0.12065 0.3048)
			(stroke
				(width 0.1)
				(type default)
			)
			(layer "F.Fab")
		)
		(fp_line
			(start 0.120396 0.2794)
			(end -0.12065 0.2794)
			(stroke
				(width 0.1)
				(type default)
			)
			(layer "F.Fab")
		)
		(fp_line
			(start -0.12065 -0.2794)
			(end 0.12065 -0.2794)
			(stroke
				(width 0.1)
				(type default)
			)
			(layer "F.Fab")
		)
		(fp_line
			(start 0.12065 -0.2794)
			(end 0.12065 -0.3048)
			(stroke
				(width 0.1)
				(type default)
			)
			(layer "F.Fab")
		)
		(fp_line
			(start 0.12065 -0.3048)
			(end 0.67945 -0.3048)
			(stroke
				(width 0.1)
				(type default)
			)
			(layer "F.Fab")
		)
		(fp_line
			(start 0.67945 -0.3048)
			(end 0.67945 0.3048)
			(stroke
				(width 0.1)
				(type default)
			)
			(layer "F.Fab")
		)
		(fp_line
			(start -0.67945 -0.305054)
			(end -0.12065 -0.305054)
			(stroke
				(width 0.1)
				(type default)
			)
			(layer "F.Fab")
		)
		(fp_line
			(start -0.12065 -0.305054)
			(end -0.12065 -0.2794)
			(stroke
				(width 0.1)
				(type default)
			)
			(layer "F.Fab")
		)
		(pad "1" smd circle
			(at -0.40005 0 270)
			(size 0 0)
			(layers "F.Cu" "F.Mask" "F.Paste")
			(net "LED_FM_PCH_SLP_S4_N")
		)
		(pad "2" smd circle
			(at 0.40005 0 270)
			(size 0 0)
			(layers "F.Cu" "F.Mask" "F.Paste")
			(net "P3V3_AUX")
		)
	)
	(footprint ""
		(layer "F.Cu")
		(at 122.390154 -408.517344 -90)
		(property "Reference" "C1517"
			(at 0 0 270)
			(layer "F.SilkS")
			(hide yes)
			(effects
				(font
					(size 1.27 1.27)
				)
			)
		)
		(property "Value" ""
			(at 0 0 270)
			(layer "F.Fab")
			(effects
				(font
					(size 1.27 1.27)
				)
			)
		)
		(duplicate_pad_numbers_are_jumpers no)
		(fp_line
			(start -0.299974 0.150114)
			(end -0.299974 -0.150114)
			(stroke
				(width 0.1)
				(type default)
			)
			(layer "F.Fab")
		)
		(fp_line
			(start 0.299974 0.150114)
			(end -0.299974 0.150114)
			(stroke
				(width 0.1)
				(type default)
			)
			(layer "F.Fab")
		)
		(fp_line
			(start -0.299974 -0.150114)
			(end 0.299974 -0.150114)
			(stroke
				(width 0.1)
				(type default)
			)
			(layer "F.Fab")
		)
		(fp_line
			(start 0.299974 -0.150114)
			(end 0.299974 0.150114)
			(stroke
				(width 0.1)
				(type default)
			)
			(layer "F.Fab")
		)
		(pad "1" smd rect
			(at -0.2667 0 270)
			(size 0.3048 0.381)
			(layers "F.Cu" "F.Mask" "F.Paste")
			(net "P5E_CPU1_PE3_TX_C_DP<15>")
		)
		(pad "2" smd rect
			(at 0.2667 0 270)
			(size 0.3048 0.381)
			(layers "F.Cu" "F.Mask" "F.Paste")
			(net "P5E_CPU1_PE3_TX_DP<15>")
		)
	)
	(footprint ""
		(layer "F.Cu")
		(at 54.242716 -116.134388 180)
		(property "Reference" "R3707"
			(at 0 0 180)
			(layer "F.SilkS")
			(hide yes)
			(effects
				(font
					(size 1.27 1.27)
				)
			)
		)
		(property "Value" ""
			(at 0 0 180)
			(layer "F.Fab")
			(effects
				(font
					(size 1.27 1.27)
				)
			)
		)
		(duplicate_pad_numbers_are_jumpers no)
		(fp_line
			(start 0.7874 0.4064)
			(end -0.7874 0.4064)
			(stroke
				(width 0.1524)
				(type default)
			)
			(layer "F.SilkS")
		)
		(fp_line
			(start 0.7874 -0.4064)
			(end 0.7874 0.4064)
			(stroke
				(width 0.1524)
				(type default)
			)
			(layer "F.SilkS")
		)
		(fp_line
			(start -0.7874 0.4064)
			(end -0.7874 -0.4064)
			(stroke
				(width 0.1524)
				(type default)
			)
			(layer "F.SilkS")
		)
		(fp_line
			(start -0.7874 -0.4064)
			(end 0.7874 -0.4064)
			(stroke
				(width 0.1524)
				(type default)
			)
			(layer "F.SilkS")
		)
		(fp_line
			(start 0.67945 0.3048)
			(end 0.120396 0.3048)
			(stroke
				(width 0.1)
				(type default)
			)
			(layer "F.Fab")
		)
		(fp_line
			(start 0.67945 -0.3048)
			(end 0.67945 0.3048)
			(stroke
				(width 0.1)
				(type default)
			)
			(layer "F.Fab")
		)
		(fp_line
			(start 0.12065 -0.2794)
			(end 0.12065 -0.3048)
			(stroke
				(width 0.1)
				(type default)
			)
			(layer "F.Fab")
		)
		(fp_line
			(start 0.12065 -0.3048)
			(end 0.67945 -0.3048)
			(stroke
				(width 0.1)
				(type default)
			)
			(layer "F.Fab")
		)
		(fp_line
			(start 0.120396 0.3048)
			(end 0.120396 0.2794)
			(stroke
				(width 0.1)
				(type default)
			)
			(layer "F.Fab")
		)
		(fp_line
			(start 0.120396 0.2794)
			(end -0.12065 0.2794)
			(stroke
				(width 0.1)
				(type default)
			)
			(layer "F.Fab")
		)
		(fp_line
			(start -0.12065 0.3048)
			(end -0.67945 0.3048)
			(stroke
				(width 0.1)
				(type default)
			)
			(layer "F.Fab")
		)
		(fp_line
			(start -0.12065 0.2794)
			(end -0.12065 0.3048)
			(stroke
				(width 0.1)
				(type default)
			)
			(layer "F.Fab")
		)
		(fp_line
			(start -0.12065 -0.2794)
			(end 0.12065 -0.2794)
			(stroke
				(width 0.1)
				(type default)
			)
			(layer "F.Fab")
		)
		(fp_line
			(start -0.12065 -0.305054)
			(end -0.12065 -0.2794)
			(stroke
				(width 0.1)
				(type default)
			)
			(layer "F.Fab")
		)
		(fp_line
			(start -0.67945 0.3048)
			(end -0.67945 -0.305054)
			(stroke
				(width 0.1)
				(type default)
			)
			(layer "F.Fab")
		)
		(fp_line
			(start -0.67945 -0.305054)
			(end -0.12065 -0.305054)
			(stroke
				(width 0.1)
				(type default)
			)
			(layer "F.Fab")
		)
		(pad "1" smd circle
			(at -0.40005 0 180)
			(size 0 0)
			(layers "F.Cu" "F.Mask" "F.Paste")
			(net "PCA9548_PCIE0_ADDR1")
		)
		(pad "2" smd circle
			(at 0.40005 0 180)
			(size 0 0)
			(layers "F.Cu" "F.Mask" "F.Paste")
			(net "GND")
		)
	)
)
